(kicad_pcb
	(version 20260206)
	(generator "pcbnew")
	(generator_version "10.0")
	(general
		(thickness 1.6)
		(legacy_teardrops no)
	)
	(paper "A4")
	(title_block
		(title "12092022_DA0F0TFB6D0_F0T_FAN_BOARD_MP5048_D_brd_v02_OCP.brd")
		(comment 1 "Grand Teton / footprints 684-691 of 924")
	)
	(layers
		(0 "F.Cu" signal "TOP")
		(4 "In1.Cu" signal "GND")
		(6 "In2.Cu" signal "IN1")
		(8 "In3.Cu" signal "IN2")
		(10 "In4.Cu" signal "GND1")
		(2 "B.Cu" signal "BOTTOM")
		(9 "F.Adhes" user "F.Adhesive")
		(11 "B.Adhes" user "B.Adhesive")
		(13 "F.Paste" user "Package Geometry/Pastemask Top")
		(15 "B.Paste" user "Package Geometry/Pastemask Bottom")
		(5 "F.SilkS" user "Ref Des/Silkscreen Top")
		(7 "B.SilkS" user "Ref Des/Silkscreen Bottom")
		(1 "F.Mask" user "Board Geometry/Soldermask Top")
		(3 "B.Mask" user "Board Geometry/Soldermask Bottom")
		(17 "Dwgs.User" user "User.Drawings")
		(19 "Cmts.User" user "User.Comments")
		(21 "Eco1.User" user "User.Eco1")
		(23 "Eco2.User" user "User.Eco2")
		(25 "Edge.Cuts" user "Board Geometry/Outline")
		(27 "Margin" user)
		(31 "F.CrtYd" user "Package Geometry/Place Bound Top")
		(29 "B.CrtYd" user "Package Geometry/Place Bound Bottom")
		(35 "F.Fab" user "Ref Des/Assembly Top")
		(33 "B.Fab" user "Ref Des/Assembly Bottom")
	)
	(footprint ""
		(layer "F.Cu")
		(at 18.288 -195.961 -90)
		(property "Reference" "R5318"
			(at 0 0 270)
			(layer "F.SilkS")
			(hide yes)
			(effects
				(font
					(size 1.27 1.27)
				)
			)
		)
		(property "Value" ""
			(at 0 0 270)
			(layer "F.Fab")
			(effects
				(font
					(size 1.27 1.27)
				)
			)
		)
		(duplicate_pad_numbers_are_jumpers no)
		(fp_line
			(start -0.7874 0.4064)
			(end -0.7874 -0.4064)
			(stroke
				(width 0.1524)
				(type default)
			)
			(layer "F.SilkS")
		)
		(fp_line
			(start 0.7874 0.4064)
			(end -0.7874 0.4064)
			(stroke
				(width 0.1524)
				(type default)
			)
			(layer "F.SilkS")
		)
		(fp_line
			(start -0.7874 -0.4064)
			(end 0.7874 -0.4064)
			(stroke
				(width 0.1524)
				(type default)
			)
			(layer "F.SilkS")
		)
		(fp_line
			(start 0.7874 -0.4064)
			(end 0.7874 0.4064)
			(stroke
				(width 0.1524)
				(type default)
			)
			(layer "F.SilkS")
		)
		(fp_line
			(start -0.67945 0.3048)
			(end -0.67945 -0.305054)
			(stroke
				(width 0.1)
				(type default)
			)
			(layer "F.Fab")
		)
		(fp_line
			(start -0.12065 0.3048)
			(end -0.67945 0.3048)
			(stroke
				(width 0.1)
				(type default)
			)
			(layer "F.Fab")
		)
		(fp_line
			(start 0.120396 0.3048)
			(end 0.120396 0.2794)
			(stroke
				(width 0.1)
				(type default)
			)
			(layer "F.Fab")
		)
		(fp_line
			(start 0.67945 0.3048)
			(end 0.120396 0.3048)
			(stroke
				(width 0.1)
				(type default)
			)
			(layer "F.Fab")
		)
		(fp_line
			(start -0.12065 0.2794)
			(end -0.12065 0.3048)
			(stroke
				(width 0.1)
				(type default)
			)
			(layer "F.Fab")
		)
		(fp_line
			(start 0.120396 0.2794)
			(end -0.12065 0.2794)
			(stroke
				(width 0.1)
				(type default)
			)
			(layer "F.Fab")
		)
		(fp_line
			(start -0.12065 -0.2794)
			(end 0.12065 -0.2794)
			(stroke
				(width 0.1)
				(type default)
			)
			(layer "F.Fab")
		)
		(fp_line
			(start 0.12065 -0.2794)
			(end 0.12065 -0.3048)
			(stroke
				(width 0.1)
				(type default)
			)
			(layer "F.Fab")
		)
		(fp_line
			(start 0.12065 -0.3048)
			(end 0.67945 -0.3048)
			(stroke
				(width 0.1)
				(type default)
			)
			(layer "F.Fab")
		)
		(fp_line
			(start 0.67945 -0.3048)
			(end 0.67945 0.3048)
			(stroke
				(width 0.1)
				(type default)
			)
			(layer "F.Fab")
		)
		(fp_line
			(start -0.67945 -0.305054)
			(end -0.12065 -0.305054)
			(stroke
				(width 0.1)
				(type default)
			)
			(layer "F.Fab")
		)
		(fp_line
			(start -0.12065 -0.305054)
			(end -0.12065 -0.2794)
			(stroke
				(width 0.1)
				(type default)
			)
			(layer "F.Fab")
		)
		(pad "1" smd rect
			(at -0.40005 0 90)
			(size 0.4572 0.508)
			(layers "F.Cu" "F.Mask" "F.Paste")
			(net "FAN_6_TACH_IL_R")
		)
		(pad "2" smd rect
			(at 0.40005 0 90)
			(size 0.4572 0.508)
			(layers "F.Cu" "F.Mask" "F.Paste")
			(net "FAN_6_TACH_IL")
		)
	)
	(footprint ""
		(layer "F.Cu")
		(at 26.373582 -260.139434)
		(property "Reference" "ME4"
			(at 0 0 0)
			(layer "F.SilkS")
			(hide yes)
			(effects
				(font
					(size 1.27 1.27)
				)
			)
		)
		(property "Value" ""
			(at 0 0 0)
			(layer "F.Fab")
			(effects
				(font
					(size 1.27 1.27)
				)
			)
		)
		(duplicate_pad_numbers_are_jumpers no)
		(fp_poly
			(pts
				(xy 0 -0.5842) (xy 3.3401 -0.5842) (xy 3.3401 0) (xy 0 0)
			)
			(stroke
				(width 0)
				(type default)
			)
			(fill yes)
			(layer "F.SilkS")
		)
		(fp_poly
			(pts
				(xy 1.32715 -3.4417) (xy 2.01295 -3.4417) (xy 2.01295 -3.2512) (xy 1.32715 -3.2512)
			)
			(stroke
				(width 0)
				(type default)
			)
			(fill yes)
			(layer "F.SilkS")
		)
		(fp_poly
			(pts
				(xy -0.070612 -0.681228) (xy -0.197612 -0.820928) (xy 0.852678 -1.91262) (xy 0.728472 -3.29184)
				(xy -0.248412 -4.300728) (xy -0.184912 -4.478528) (xy -0.007112 -4.503928) (xy 0.684022 -3.785616)
				(xy 0.65659 -4.0894) (xy 0.97155 -4.3434) (xy 1.22555 -4.3561) (xy 1.46685 -4.4704) (xy 2.01295 -4.4704)
				(xy 2.15265 -4.4069) (xy 2.44475 -4.191) (xy 2.49555 -4.191) (xy 2.59715 -4.2926) (xy 2.80035 -4.2672)
				(xy 2.88925 -4.1656) (xy 2.88925 -4.029456) (xy 3.345688 -4.503928) (xy 3.523488 -4.478528) (xy 3.586988 -4.300728)
				(xy 2.88925 -3.58013) (xy 2.88925 -3.3147) (xy 2.82575 -3.2385) (xy 2.67335 -3.2385) (xy 2.521966 -1.875282)
				(xy 2.545842 -1.85039)
				(arc
					(start 2.55905 -1.8415)
					(mid 2.648099 -1.766068)
					(end 2.717292 -1.672082)
				)
				(xy 3.536188 -0.820928) (xy 3.409188 -0.681228) (xy 3.244088 -0.693928)
				(arc
					(start 2.737612 -1.216914)
					(mid 2.31728 -0.925553)
					(end 1.86055 -1.1557)
				)
				(xy 0.92075 -1.1557) (xy 0.888492 -1.51384) (xy 0.094488 -0.693928)
			)
			(stroke
				(width 0)
				(type default)
			)
			(fill yes)
			(layer "F.SilkS")
		)
	)
	(footprint ""
		(layer "F.Cu")
		(at 37.338 -297.053)
		(property "Reference" "R5690"
			(at 0 0 0)
			(layer "F.SilkS")
			(hide yes)
			(effects
				(font
					(size 1.27 1.27)
				)
			)
		)
		(property "Value" ""
			(at 0 0 0)
			(layer "F.Fab")
			(effects
				(font
					(size 1.27 1.27)
				)
			)
		)
		(duplicate_pad_numbers_are_jumpers no)
		(fp_line
			(start -0.7874 -0.4064)
			(end 0.7874 -0.4064)
			(stroke
				(width 0.1524)
				(type default)
			)
			(layer "F.SilkS")
		)
		(fp_line
			(start -0.7874 0.4064)
			(end -0.7874 -0.4064)
			(stroke
				(width 0.1524)
				(type default)
			)
			(layer "F.SilkS")
		)
		(fp_line
			(start 0.7874 -0.4064)
			(end 0.7874 0.4064)
			(stroke
				(width 0.1524)
				(type default)
			)
			(layer "F.SilkS")
		)
		(fp_line
			(start 0.7874 0.4064)
			(end -0.7874 0.4064)
			(stroke
				(width 0.1524)
				(type default)
			)
			(layer "F.SilkS")
		)
		(fp_line
			(start -0.67945 -0.305054)
			(end -0.12065 -0.305054)
			(stroke
				(width 0.1)
				(type default)
			)
			(layer "F.Fab")
		)
		(fp_line
			(start -0.67945 0.3048)
			(end -0.67945 -0.305054)
			(stroke
				(width 0.1)
				(type default)
			)
			(layer "F.Fab")
		)
		(fp_line
			(start -0.12065 -0.305054)
			(end -0.12065 -0.2794)
			(stroke
				(width 0.1)
				(type default)
			)
			(layer "F.Fab")
		)
		(fp_line
			(start -0.12065 -0.2794)
			(end 0.12065 -0.2794)
			(stroke
				(width 0.1)
				(type default)
			)
			(layer "F.Fab")
		)
		(fp_line
			(start -0.12065 0.2794)
			(end -0.12065 0.3048)
			(stroke
				(width 0.1)
				(type default)
			)
			(layer "F.Fab")
		)
		(fp_line
			(start -0.12065 0.3048)
			(end -0.67945 0.3048)
			(stroke
				(width 0.1)
				(type default)
			)
			(layer "F.Fab")
		)
		(fp_line
			(start 0.120396 0.2794)
			(end -0.12065 0.2794)
			(stroke
				(width 0.1)
				(type default)
			)
			(layer "F.Fab")
		)
		(fp_line
			(start 0.120396 0.3048)
			(end 0.120396 0.2794)
			(stroke
				(width 0.1)
				(type default)
			)
			(layer "F.Fab")
		)
		(fp_line
			(start 0.12065 -0.3048)
			(end 0.67945 -0.3048)
			(stroke
				(width 0.1)
				(type default)
			)
			(layer "F.Fab")
		)
		(fp_line
			(start 0.12065 -0.2794)
			(end 0.12065 -0.3048)
			(stroke
				(width 0.1)
				(type default)
			)
			(layer "F.Fab")
		)
		(fp_line
			(start 0.67945 -0.3048)
			(end 0.67945 0.3048)
			(stroke
				(width 0.1)
				(type default)
			)
			(layer "F.Fab")
		)
		(fp_line
			(start 0.67945 0.3048)
			(end 0.120396 0.3048)
			(stroke
				(width 0.1)
				(type default)
			)
			(layer "F.Fab")
		)
		(pad "1" smd rect
			(at -0.40005 0 180)
			(size 0.4572 0.508)
			(layers "F.Cu" "F.Mask" "F.Paste")
			(net "P12V_LED_R_FAN0")
		)
		(pad "2" smd rect
			(at 0.40005 0 180)
			(size 0.4572 0.508)
			(layers "F.Cu" "F.Mask" "F.Paste")
			(net "P12V_LED_R1_FAN0")
		)
	)
	(footprint ""
		(layer "F.Cu")
		(at 12.2936 -306.705)
		(property "Reference" "ME7"
			(at 0 0 0)
			(layer "F.SilkS")
			(hide yes)
			(effects
				(font
					(size 1.27 1.27)
				)
			)
		)
		(property "Value" ""
			(at 0 0 0)
			(layer "F.Fab")
			(effects
				(font
					(size 1.27 1.27)
				)
			)
		)
		(duplicate_pad_numbers_are_jumpers no)
		(fp_line
			(start 0 -5.999988)
			(end 0 -4.475988)
			(stroke
				(width 0.1524)
				(type default)
			)
			(layer "F.SilkS")
		)
		(fp_line
			(start 0 -1.524)
			(end 0 0)
			(stroke
				(width 0.1524)
				(type default)
			)
			(layer "F.SilkS")
		)
		(fp_line
			(start 0 0)
			(end 1.524 0)
			(stroke
				(width 0.1524)
				(type default)
			)
			(layer "F.SilkS")
		)
		(fp_line
			(start 1.524 -5.999988)
			(end 0 -5.999988)
			(stroke
				(width 0.1524)
				(type default)
			)
			(layer "F.SilkS")
		)
		(fp_line
			(start 25.475946 -5.999988)
			(end 26.999946 -5.999988)
			(stroke
				(width 0.1524)
				(type default)
			)
			(layer "F.SilkS")
		)
		(fp_line
			(start 26.999946 -5.999988)
			(end 26.999946 -4.475988)
			(stroke
				(width 0.1524)
				(type default)
			)
			(layer "F.SilkS")
		)
		(fp_line
			(start 26.999946 -1.524)
			(end 26.999946 0)
			(stroke
				(width 0.1524)
				(type default)
			)
			(layer "F.SilkS")
		)
		(fp_line
			(start 26.999946 0)
			(end 25.475946 0)
			(stroke
				(width 0.1524)
				(type default)
			)
			(layer "F.SilkS")
		)
		(fp_text user "S/N"
			(at 0.2032 -4.59105 0)
			(unlocked yes)
			(layer "F.SilkS")
			(effects
				(font
					(size 1.905 1.4224)
					(thickness 0.1524)
				)
				(justify left)
			)
		)
	)
	(footprint ""
		(layer "F.Cu")
		(at 27.432 -182.372 180)
		(property "Reference" "R5487"
			(at 0 0 180)
			(layer "F.SilkS")
			(hide yes)
			(effects
				(font
					(size 1.27 1.27)
				)
			)
		)
		(property "Value" ""
			(at 0 0 180)
			(layer "F.Fab")
			(effects
				(font
					(size 1.27 1.27)
				)
			)
		)
		(duplicate_pad_numbers_are_jumpers no)
		(fp_line
			(start 0.7874 0.4064)
			(end -0.7874 0.4064)
			(stroke
				(width 0.1524)
				(type default)
			)
			(layer "F.SilkS")
		)
		(fp_line
			(start 0.7874 -0.4064)
			(end 0.7874 0.4064)
			(stroke
				(width 0.1524)
				(type default)
			)
			(layer "F.SilkS")
		)
		(fp_line
			(start -0.7874 0.4064)
			(end -0.7874 -0.4064)
			(stroke
				(width 0.1524)
				(type default)
			)
			(layer "F.SilkS")
		)
		(fp_line
			(start -0.7874 -0.4064)
			(end 0.7874 -0.4064)
			(stroke
				(width 0.1524)
				(type default)
			)
			(layer "F.SilkS")
		)
		(fp_line
			(start 0.67945 0.3048)
			(end 0.120396 0.3048)
			(stroke
				(width 0.1)
				(type default)
			)
			(layer "F.Fab")
		)
		(fp_line
			(start 0.67945 -0.3048)
			(end 0.67945 0.3048)
			(stroke
				(width 0.1)
				(type default)
			)
			(layer "F.Fab")
		)
		(fp_line
			(start 0.12065 -0.2794)
			(end 0.12065 -0.3048)
			(stroke
				(width 0.1)
				(type default)
			)
			(layer "F.Fab")
		)
		(fp_line
			(start 0.12065 -0.3048)
			(end 0.67945 -0.3048)
			(stroke
				(width 0.1)
				(type default)
			)
			(layer "F.Fab")
		)
		(fp_line
			(start 0.120396 0.3048)
			(end 0.120396 0.2794)
			(stroke
				(width 0.1)
				(type default)
			)
			(layer "F.Fab")
		)
		(fp_line
			(start 0.120396 0.2794)
			(end -0.12065 0.2794)
			(stroke
				(width 0.1)
				(type default)
			)
			(layer "F.Fab")
		)
		(fp_line
			(start -0.12065 0.3048)
			(end -0.67945 0.3048)
			(stroke
				(width 0.1)
				(type default)
			)
			(layer "F.Fab")
		)
		(fp_line
			(start -0.12065 0.2794)
			(end -0.12065 0.3048)
			(stroke
				(width 0.1)
				(type default)
			)
			(layer "F.Fab")
		)
		(fp_line
			(start -0.12065 -0.2794)
			(end 0.12065 -0.2794)
			(stroke
				(width 0.1)
				(type default)
			)
			(layer "F.Fab")
		)
		(fp_line
			(start -0.12065 -0.305054)
			(end -0.12065 -0.2794)
			(stroke
				(width 0.1)
				(type default)
			)
			(layer "F.Fab")
		)
		(fp_line
			(start -0.67945 0.3048)
			(end -0.67945 -0.305054)
			(stroke
				(width 0.1)
				(type default)
			)
			(layer "F.Fab")
		)
		(fp_line
			(start -0.67945 -0.305054)
			(end -0.12065 -0.305054)
			(stroke
				(width 0.1)
				(type default)
			)
			(layer "F.Fab")
		)
		(pad "1" smd circle
			(at -0.40005 0 180)
			(size 0 0)
			(layers "F.Cu" "F.Mask" "F.Paste")
			(net "P52V_FAN_0_BUFF_EN")
		)
		(pad "2" smd circle
			(at 0.40005 0 180)
			(size 0 0)
			(layers "F.Cu" "F.Mask" "F.Paste")
			(net "P52V_FAN_0_BUFF_EN_R")
		)
	)
	(footprint ""
		(layer "F.Cu")
		(at 34.417 -22.606)
		(property "Reference" "U374"
			(at -4.6482 -0.98933 0)
			(unlocked yes)
			(layer "F.SilkS")
			(effects
				(font
					(size 0.7874 0.5842)
					(thickness 0.1524)
				)
				(justify left)
			)
		)
		(property "Value" ""
			(at 0 0 0)
			(layer "F.Fab")
			(effects
				(font
					(size 1.27 1.27)
				)
			)
		)
		(duplicate_pad_numbers_are_jumpers no)
		(fp_line
			(start -1.335278 -1.100074)
			(end -1.335278 1.100074)
			(stroke
				(width 0.1524)
				(type default)
			)
			(layer "F.SilkS")
		)
		(fp_line
			(start -1.335278 1.100074)
			(end 1.335278 1.100074)
			(stroke
				(width 0.1524)
				(type default)
			)
			(layer "F.SilkS")
		)
		(fp_line
			(start 1.335278 -1.100074)
			(end -1.335278 -1.100074)
			(stroke
				(width 0.1524)
				(type default)
			)
			(layer "F.SilkS")
		)
		(fp_line
			(start 1.335278 1.100074)
			(end 1.335278 -1.100074)
			(stroke
				(width 0.1524)
				(type default)
			)
			(layer "F.SilkS")
		)
		(fp_line
			(start -0.674878 -1.100074)
			(end -0.674878 1.100074)
			(stroke
				(width 0.1)
				(type default)
			)
			(layer "F.Fab")
		)
		(fp_line
			(start -0.674878 1.100074)
			(end 0.674878 1.100074)
			(stroke
				(width 0.1)
				(type default)
			)
			(layer "F.Fab")
		)
		(fp_line
			(start 0.674878 -1.100074)
			(end -0.674878 -1.100074)
			(stroke
				(width 0.1)
				(type default)
			)
			(layer "F.Fab")
		)
		(fp_line
			(start 0.674878 1.100074)
			(end 0.674878 -1.100074)
			(stroke
				(width 0.1)
				(type default)
			)
			(layer "F.Fab")
		)
		(pad "D" smd rect
			(at 0.8001 0 270)
			(size 0.6096 0.8128)
			(layers "F.Cu" "F.Mask" "F.Paste")
			(net "FAN_3_FAIL_LED_R_N")
		)
		(pad "G" smd rect
			(at -0.8001 -0.649986 270)
			(size 0.6096 0.8128)
			(layers "F.Cu" "F.Mask" "F.Paste")
			(net "FAN_3_FAIL_R_LED")
		)
		(pad "S" smd rect
			(at -0.8001 0.649986 270)
			(size 0.6096 0.8128)
			(layers "F.Cu" "F.Mask" "F.Paste")
			(net "GND")
		)
	)
	(footprint ""
		(layer "F.Cu")
		(at 48.019716 -36.101274 90)
		(property "Reference" "C2048"
			(at 0 0 90)
			(layer "F.SilkS")
			(hide yes)
			(effects
				(font
					(size 1.27 1.27)
				)
			)
		)
		(property "Value" ""
			(at 0 0 90)
			(layer "F.Fab")
			(effects
				(font
					(size 1.27 1.27)
				)
			)
		)
		(duplicate_pad_numbers_are_jumpers no)
		(fp_line
			(start 1.524 -0.762)
			(end 1.524 0.762)
			(stroke
				(width 0.1524)
				(type default)
			)
			(layer "F.SilkS")
		)
		(fp_line
			(start -1.524 -0.762)
			(end 1.524 -0.762)
			(stroke
				(width 0.1524)
				(type default)
			)
			(layer "F.SilkS")
		)
		(fp_line
			(start 1.524 0.762)
			(end -1.524 0.762)
			(stroke
				(width 0.1524)
				(type default)
			)
			(layer "F.SilkS")
		)
		(fp_line
			(start -1.524 0.762)
			(end -1.524 -0.762)
			(stroke
				(width 0.1524)
				(type default)
			)
			(layer "F.SilkS")
		)
		(fp_line
			(start 1.1049 -0.724916)
			(end -1.1049 -0.724916)
			(stroke
				(width 0.1)
				(type default)
			)
			(layer "F.Fab")
		)
		(fp_line
			(start -1.1049 -0.724916)
			(end -1.1049 0.724916)
			(stroke
				(width 0.1)
				(type default)
			)
			(layer "F.Fab")
		)
		(fp_line
			(start 1.1049 0.724916)
			(end 1.1049 -0.724916)
			(stroke
				(width 0.1)
				(type default)
			)
			(layer "F.Fab")
		)
		(fp_line
			(start -1.1049 0.724916)
			(end 1.1049 0.724916)
			(stroke
				(width 0.1)
				(type default)
			)
			(layer "F.Fab")
		)
		(pad "1" smd rect
			(at -0.889 0 270)
			(size 1.016 1.27)
			(layers "F.Cu" "F.Mask" "F.Paste")
			(net "P12V_LED_FAN3")
		)
		(pad "2" smd rect
			(at 0.889 0 270)
			(size 1.016 1.27)
			(layers "F.Cu" "F.Mask" "F.Paste")
			(net "GND")
		)
	)
	(footprint ""
		(layer "F.Cu")
		(at 42.037 -182.88)
		(property "Reference" "R520"
			(at 0 0 0)
			(layer "F.SilkS")
			(hide yes)
			(effects
				(font
					(size 1.27 1.27)
				)
			)
		)
		(property "Value" ""
			(at 0 0 0)
			(layer "F.Fab")
			(effects
				(font
					(size 1.27 1.27)
				)
			)
		)
		(duplicate_pad_numbers_are_jumpers no)
		(fp_line
			(start -0.7874 -0.4064)
			(end 0.7874 -0.4064)
			(stroke
				(width 0.1524)
				(type default)
			)
			(layer "F.SilkS")
		)
		(fp_line
			(start -0.7874 0.4064)
			(end -0.7874 -0.4064)
			(stroke
				(width 0.1524)
				(type default)
			)
			(layer "F.SilkS")
		)
		(fp_line
			(start 0.7874 -0.4064)
			(end 0.7874 0.4064)
			(stroke
				(width 0.1524)
				(type default)
			)
			(layer "F.SilkS")
		)
		(fp_line
			(start 0.7874 0.4064)
			(end -0.7874 0.4064)
			(stroke
				(width 0.1524)
				(type default)
			)
			(layer "F.SilkS")
		)
		(fp_line
			(start -0.67945 -0.305054)
			(end -0.12065 -0.305054)
			(stroke
				(width 0.1)
				(type default)
			)
			(layer "F.Fab")
		)
		(fp_line
			(start -0.67945 0.3048)
			(end -0.67945 -0.305054)
			(stroke
				(width 0.1)
				(type default)
			)
			(layer "F.Fab")
		)
		(fp_line
			(start -0.12065 -0.305054)
			(end -0.12065 -0.2794)
			(stroke
				(width 0.1)
				(type default)
			)
			(layer "F.Fab")
		)
		(fp_line
			(start -0.12065 -0.2794)
			(end 0.12065 -0.2794)
			(stroke
				(width 0.1)
				(type default)
			)
			(layer "F.Fab")
		)
		(fp_line
			(start -0.12065 0.2794)
			(end -0.12065 0.3048)
			(stroke
				(width 0.1)
				(type default)
			)
			(layer "F.Fab")
		)
		(fp_line
			(start -0.12065 0.3048)
			(end -0.67945 0.3048)
			(stroke
				(width 0.1)
				(type default)
			)
			(layer "F.Fab")
		)
		(fp_line
			(start 0.120396 0.2794)
			(end -0.12065 0.2794)
			(stroke
				(width 0.1)
				(type default)
			)
			(layer "F.Fab")
		)
		(fp_line
			(start 0.120396 0.3048)
			(end 0.120396 0.2794)
			(stroke
				(width 0.1)
				(type default)
			)
			(layer "F.Fab")
		)
		(fp_line
			(start 0.12065 -0.3048)
			(end 0.67945 -0.3048)
			(stroke
				(width 0.1)
				(type default)
			)
			(layer "F.Fab")
		)
		(fp_line
			(start 0.12065 -0.2794)
			(end 0.12065 -0.3048)
			(stroke
				(width 0.1)
				(type default)
			)
			(layer "F.Fab")
		)
		(fp_line
			(start 0.67945 -0.3048)
			(end 0.67945 0.3048)
			(stroke
				(width 0.1)
				(type default)
			)
			(layer "F.Fab")
		)
		(fp_line
			(start 0.67945 0.3048)
			(end 0.120396 0.3048)
			(stroke
				(width 0.1)
				(type default)
			)
			(layer "F.Fab")
		)
		(pad "1" smd circle
			(at -0.40005 0)
			(size 0 0)
			(layers "F.Cu" "F.Mask" "F.Paste")
			(net "PD_FAN_BUFF_INPUT_U336F")
		)
		(pad "2" smd circle
			(at 0.40005 0)
			(size 0 0)
			(layers "F.Cu" "F.Mask" "F.Paste")
			(net "P3V3_AUX")
		)
	)
)
